FILE_TYPE = CONNECTIVITY;
{Allegro Design Entry HDL 17.4-2019 S026 (4007227) 1/17/2022}
"PAGE_NUMBER" = 59;
0"NC";
1"GND\g";
2"GND\g";
3"GND\g";
4"GND\g";
5"GND\g";
6"GND\g";
7"GND\g";
8"GND\g";
%"GENOA_SP5"
"34","(-7975,3500)","0","pure_quanta","I1";
;
LOCATION"U26"
$SEC"34"
CDS_SEC"34"
PART_TYPE"SMLF"
MATERIAL"IO"
VALUE"SOCKET6096_13568-001"
CDS_LIB"pure_quanta"
CDS_LMAN_SYM_OUTLINE"-400,3050,400,-3050"
NEEDS_NO_SIZE"TRUE"
PART_NUMBER"DGA^6000030";
"VSS_BV45"
$PN"BV45"2;
"VSS_BV44"
$PN"BV44"2;
"VSS_BV43"
$PN"BV43"2;
"VSS_BV39"
$PN"BV39"2;
"VSS_BV34"
$PN"BV34"2;
"VSS_BV33"
$PN"BV33"2;
"VSS_BV32"
$PN"BV32"2;
"VSS_BV31"
$PN"BV31"2;
"VSS_BV30"
$PN"BV30"2;
"VSS_BV29"
$PN"BV29"2;
"VSS_BV28"
$PN"BV28"2;
"VSS_BV27"
$PN"BV27"2;
"VSS_BV26"
$PN"BV26"2;
"VSS_BV25"
$PN"BV25"2;
"VSS_BV24"
$PN"BV24"2;
"VSS_BV23"
$PN"BV23"2;
"VSS_BV17"
$PN"BV17"2;
"VSS_BV15"
$PN"BV15"2;
"VSS_BV10"
$PN"BV10"2;
"VSS_BV8"
$PN"BV8"2;
"VSS_BV3"
$PN"BV3"2;
"VSS_BU75"
$PN"BU75"2;
"VSS_BU72"
$PN"BU72"2;
"VSS_BU70"
$PN"BU70"2;
"VSS_BU68"
$PN"BU68"2;
"VSS_BU65"
$PN"BU65"2;
"VSS_BU63"
$PN"BU63"2;
"VSS_BU61"
$PN"BU61"2;
"VSS_BU58"
$PN"BU58"2;
"VSS_BU56"
$PN"BU56"2;
"VSS_BU54"
$PN"BU54"2;
"VSS_BU51"
$PN"BU51"2;
"VSS_BU48"
$PN"BU48"2;
"VSS_BU45"
$PN"BU45"2;
"VSS_BU42"
$PN"BU42"2;
"VSS_BU41"
$PN"BU41"2;
"VSS_BU40"
$PN"BU40"2;
"VSS_BU36"
$PN"BU36"2;
"VSS_BU35"
$PN"BU35"2;
"VSS_BU34"
$PN"BU34"2;
"VSS_BU31"
$PN"BU31"2;
"VSS_BU28"
$PN"BU28"2;
"VSS_BU25"
$PN"BU25"2;
"VSS_BU22"
$PN"BU22"2;
"VSS_BU20"
$PN"BU20"2;
"VSS_BU18"
$PN"BU18"2;
"VSS_BU15"
$PN"BU15"2;
"VSS_BU13"
$PN"BU13"2;
"VSS_BU11"
$PN"BU11"2;
"VSS_BU8"
$PN"BU8"2;
"VSS_BU6"
$PN"BU6"2;
"VSS_BU4"
$PN"BU4"2;
"VSS_BU1"
$PN"BU1"2;
"VSS_BT73"
$PN"BT73"2;
"VSS_BT72"
$PN"BT72"2;
"VSS_BT71"
$PN"BT71"2;
"VSS_BT69"
$PN"BT69"2;
"VSS_BT68"
$PN"BT68"2;
"VSS_BT66"
$PN"BT66"2;
"VSS_BT65"
$PN"BT65"2;
"VSS_BT64"
$PN"BT64"2;
"VSS_BT62"
$PN"BT62"2;
"VSS_BT61"
$PN"BT61"2;
"VSS_BT59"
$PN"BT59"2;
"VSS_BT58"
$PN"BT58"2;
"VSS_BT57"
$PN"BT57"2;
"VSS_BT55"
$PN"BT55"2;
"VSS_BT54"
$PN"BT54"2;
"VSS_BT51"
$PN"BT51"2;
"VSS_BT48"
$PN"BT48"2;
"VSS_BT45"
$PN"BT45"2;
"VSS_BT42"
$PN"BT42"2;
"VSS_BT39"
$PN"BT39"2;
"VSS_BT37"
$PN"BT37"2;
"VSS_BT34"
$PN"BT34"2;
"VSS_BT31"
$PN"BT31"2;
"VSS_BT28"
$PN"BT28"2;
"VSS_BT25"
$PN"BT25"2;
"VSS_BT22"
$PN"BT22"2;
"VSS_BT21"
$PN"BT21"2;
"VSS_BT19"
$PN"BT19"2;
"VSS_BT18"
$PN"BT18"2;
"VSS_BT17"
$PN"BT17"2;
"VSS_BT15"
$PN"BT15"2;
"VSS_BT14"
$PN"BT14"2;
"VSS_BT12"
$PN"BT12"2;
"VSS_BT11"
$PN"BT11"2;
"VSS_BT10"
$PN"BT10"2;
"VSS_BT8"
$PN"BT8"2;
"VSS_BT7"
$PN"BT7"2;
"VSS_BT5"
$PN"BT5"2;
"VSS_BT4"
$PN"BT4"2;
"VSS_BT3"
$PN"BT3"2;
"VSS_BR75"
$PN"BR75"2;
"VSS_BR73"
$PN"BR73"2;
"VSS_BR70"
$PN"BR70"2;
"VSS_BR69"
$PN"BR69"2;
"VSS_BR68"
$PN"BR68"2;
"VSS_BR66"
$PN"BR66"2;
"VSS_BR63"
$PN"BR63"2;
"VSS_BR62"
$PN"BR62"2;
"VSS_BR61"
$PN"BR61"2;
"VSS_BR59"
$PN"BR59"2;
"VSS_BR56"
$PN"BR56"2;
"VSS_BR55"
$PN"BR55"2;
"VSS_BR51"
$PN"BR51"2;
"VSS_BR49"
$PN"BR49"2;
"VSS_BR47"
$PN"BR47"2;
"VSS_BR45"
$PN"BR45"2;
"VSS_BR43"
$PN"BR43"2;
"VSS_BR41"
$PN"BR41"2;
"VSS_BR36"
$PN"BR36"2;
"VSS_BR34"
$PN"BR34"2;
"VSS_BR32"
$PN"BR32"2;
"VSS_BR30"
$PN"BR30"2;
"VSS_BR28"
$PN"BR28"2;
"VSS_BR26"
$PN"BR26"2;
"VSS_BR24"
$PN"BR24"1;
"VSS_BR22"
$PN"BR22"1;
"VSS_BR21"
$PN"BR21"1;
"VSS_BR20"
$PN"BR20"1;
"VSS_BR17"
$PN"BR17"1;
"VSS_BR15"
$PN"BR15"1;
"VSS_BR14"
$PN"BR14"1;
"VSS_BR13"
$PN"BR13"1;
"VSS_BR10"
$PN"BR10"1;
"VSS_BR8"
$PN"BR8"1;
"VSS_BR7"
$PN"BR7"1;
"VSS_BR6"
$PN"BR6"1;
"VSS_BR3"
$PN"BR3"1;
"VSS_BR1"
$PN"BR1"1;
"VSS_BP73"
$PN"BP73"1;
"VSS_BP71"
$PN"BP71"1;
"VSS_BP68"
$PN"BP68"1;
"VSS_BP66"
$PN"BP66"1;
"VSS_BP64"
$PN"BP64"1;
"VSS_BP61"
$PN"BP61"1;
"VSS_BP59"
$PN"BP59"1;
"VSS_BP57"
$PN"BP57"1;
"VSS_BP54"
$PN"BP54"1;
"VSS_BP52"
$PN"BP52"1;
"VSS_BP50"
$PN"BP50"1;
"VSS_BP48"
$PN"BP48"1;
"VSS_BP46"
$PN"BP46"1;
"VSS_BP44"
$PN"BP44"1;
"VSS_BP42"
$PN"BP42"1;
"VSS_BP40"
$PN"BP40"1;
"VSS_BP37"
$PN"BP37"1;
"VSS_BP35"
$PN"BP35"1;
"VSS_BP33"
$PN"BP33"1;
"VSS_BP31"
$PN"BP31"1;
"VSS_BP29"
$PN"BP29"1;
"VSS_BP27"
$PN"BP27"1;
"VSS_BP25"
$PN"BP25"1;
"VSS_BP23"
$PN"BP23"1;
"VSS_BP19"
$PN"BP19"1;
"VSS_BP17"
$PN"BP17"1;
"VSS_BP15"
$PN"BP15"1;
"VSS_BP12"
$PN"BP12"1;
"VSS_BP10"
$PN"BP10"1;
"VSS_BP8"
$PN"BP8"1;
"VSS_BP5"
$PN"BP5"1;
"VSS_BP3"
$PN"BP3"1;
"VSS_BN75"
$PN"BN75"1;
"VSS_BN72"
$PN"BN72"1;
"VSS_BN70"
$PN"BN70"1;
"VSS_BN68"
$PN"BN68"1;
"VSS_BN65"
$PN"BN65"1;
"VSS_BN63"
$PN"BN63"1;
"VSS_BN61"
$PN"BN61"1;
"VSS_BN58"
$PN"BN58"1;
"VSS_BN56"
$PN"BN56"1;
"VSS_BN53"
$PN"BN53"1;
"VSS_BN51"
$PN"BN51"1;
"VSS_BN49"
$PN"BN49"1;
"VSS_BN47"
$PN"BN47"1;
"VSS_BN45"
$PN"BN45"1;
"VSS_BN43"
$PN"BN43"1;
"VSS_BN41"
$PN"BN41"1;
"VSS_BN36"
$PN"BN36"1;
"VSS_BN34"
$PN"BN34"1;
"VSS_BN32"
$PN"BN32"1;
"VSS_BN30"
$PN"BN30"1;
"VSS_BN28"
$PN"BN28"1;
"VSS_BN26"
$PN"BN26"1;
"VSS_BN24"
$PN"BN24"1;
"VSS_BN22"
$PN"BN22"1;
"VSS_BN20"
$PN"BN20"1;
"VSS_BN18"
$PN"BN18"1;
"VSS_BN15"
$PN"BN15"1;
"VSS_BN13"
$PN"BN13"1;
"VSS_BN11"
$PN"BN11"1;
"VSS_BN8"
$PN"BN8"1;
"VSS_BN6"
$PN"BN6"1;
"VSS_BN4"
$PN"BN4"1;
"VSS_BN1"
$PN"BN1"1;
"VSS_BM73"
$PN"BM73"1;
"VSS_BM68"
$PN"BM68"1;
"VSS_BM66"
$PN"BM66"1;
"VSS_BM61"
$PN"BM61"1;
"VSS_BM59"
$PN"BM59"1;
"VSS_BM54"
$PN"BM54"1;
"VSS_BM52"
$PN"BM52"1;
"VSS_BM50"
$PN"BM50"1;
"VSS_BM48"
$PN"BM48"1;
"VSS_BM46"
$PN"BM46"1;
"VSS_BM44"
$PN"BM44"1;
"VSS_BM42"
$PN"BM42"1;
"VSS_BM40"
$PN"BM40"1;
"VSS_BM37"
$PN"BM37"1;
"VSS_BM35"
$PN"BM35"1;
"VSS_BM33"
$PN"BM33"1;
"VSS_BM31"
$PN"BM31"1;
"VSS_BM29"
$PN"BM29"1;
"VSS_BM27"
$PN"BM27"1;
"VSS_BM25"
$PN"BM25"1;
"VSS_BM23"
$PN"BM23"1;
"VSS_BM17"
$PN"BM17"1;
"VSS_BM15"
$PN"BM15"1;
"VSS_BM10"
$PN"BM10"1;
"VSS_BM8"
$PN"BM8"1;
"VSS_BM3"
$PN"BM3"1;
"VSS_BL75"
$PN"BL75"1;
"VSS_BL72"
$PN"BL72"1;
"VSS_BL70"
$PN"BL70"1;
"VSS_BL68"
$PN"BL68"1;
"VSS_BL65"
$PN"BL65"1;
"VSS_BL63"
$PN"BL63"1;
"VSS_BL61"
$PN"BL61"1;
"VSS_BL58"
$PN"BL58"1;
"VSS_BL56"
$PN"BL56"1;
"VSS_BL53"
$PN"BL53"1;
"VSS_BL51"
$PN"BL51"1;
"VSS_BL49"
$PN"BL49"1;
"VSS_BL28"
$PN"BL28"1;
"VSS_BL26"
$PN"BL26"1;
"VSS_BV37"
$PN"BV37"2;
%"UNIVERSAL_GND"
"1","(-6675,475)","0","pure_quanta_power","I10";
;
CDS_LIB"pure_quanta_power"
HDL_POWER"GND";
"A"3;
%"UNIVERSAL_GND"
"1","(-7250,475)","0","pure_quanta_power","I11";
;
CDS_LIB"pure_quanta_power"
HDL_POWER"GND";
"A"2;
%"UNIVERSAL_GND"
"1","(-8700,450)","0","pure_quanta_power","I12";
;
CDS_LIB"pure_quanta_power"
HDL_POWER"GND";
"A"1;
%"GENOA_SP5"
"37","(-5950,3500)","0","pure_quanta","I2";
;
LOCATION"U26"
$SEC"37"
CDS_SEC"37"
PART_TYPE"SMLF"
MATERIAL"IO"
VALUE"SOCKET6096_13568-001"
CDS_LIB"pure_quanta"
CDS_LMAN_SYM_OUTLINE"-400,3050,400,-3050"
NEEDS_NO_SIZE"TRUE"
PART_NUMBER"DGA^6000030";
"VSS_CF33"
$PN"CF33"4;
"VSS_CF32"
$PN"CF32"4;
"VSS_CF31"
$PN"CF31"4;
"VSS_CF30"
$PN"CF30"4;
"VSS_CF29"
$PN"CF29"4;
"VSS_CF28"
$PN"CF28"4;
"VSS_CF27"
$PN"CF27"4;
"VSS_CF26"
$PN"CF26"4;
"VSS_CF25"
$PN"CF25"4;
"VSS_CF24"
$PN"CF24"4;
"VSS_CF23"
$PN"CF23"4;
"VSS_CF19"
$PN"CF19"4;
"VSS_CF17"
$PN"CF17"4;
"VSS_CF15"
$PN"CF15"4;
"VSS_CF12"
$PN"CF12"4;
"VSS_CF10"
$PN"CF10"4;
"VSS_CF8"
$PN"CF8"4;
"VSS_CF5"
$PN"CF5"4;
"VSS_CF3"
$PN"CF3"4;
"VSS_CE75"
$PN"CE75"4;
"VSS_CE72"
$PN"CE72"4;
"VSS_CE70"
$PN"CE70"4;
"VSS_CE68"
$PN"CE68"4;
"VSS_CE65"
$PN"CE65"4;
"VSS_CE63"
$PN"CE63"4;
"VSS_CE61"
$PN"CE61"4;
"VSS_CE58"
$PN"CE58"4;
"VSS_CE56"
$PN"CE56"4;
"VSS_CE54"
$PN"CE54"4;
"VSS_CE51"
$PN"CE51"4;
"VSS_CE48"
$PN"CE48"4;
"VSS_CE45"
$PN"CE45"4;
"VSS_CE42"
$PN"CE42"4;
"VSS_CE41"
$PN"CE41"4;
"VSS_CE40"
$PN"CE40"4;
"VSS_CE36"
$PN"CE36"4;
"VSS_CE35"
$PN"CE35"4;
"VSS_CE34"
$PN"CE34"4;
"VSS_CE31"
$PN"CE31"4;
"VSS_CE28"
$PN"CE28"4;
"VSS_CE25"
$PN"CE25"4;
"VSS_CE22"
$PN"CE22"4;
"VSS_CE20"
$PN"CE20"4;
"VSS_CE18"
$PN"CE18"4;
"VSS_CE15"
$PN"CE15"4;
"VSS_CE13"
$PN"CE13"4;
"VSS_CE11"
$PN"CE11"4;
"VSS_CE8"
$PN"CE8"4;
"VSS_CE6"
$PN"CE6"4;
"VSS_CE4"
$PN"CE4"4;
"VSS_CE1"
$PN"CE1"4;
"VSS_CD73"
$PN"CD73"4;
"VSS_CD68"
$PN"CD68"4;
"VSS_CD66"
$PN"CD66"4;
"VSS_CD61"
$PN"CD61"4;
"VSS_CD59"
$PN"CD59"4;
"VSS_CD54"
$PN"CD54"4;
"VSS_CD51"
$PN"CD51"4;
"VSS_CD48"
$PN"CD48"4;
"VSS_CD45"
$PN"CD45"4;
"VSS_CD42"
$PN"CD42"4;
"VSS_CD39"
$PN"CD39"4;
"VSS_CD37"
$PN"CD37"4;
"VSS_CD34"
$PN"CD34"4;
"VSS_CD31"
$PN"CD31"4;
"VSS_CD28"
$PN"CD28"4;
"VSS_CD25"
$PN"CD25"4;
"VSS_CD22"
$PN"CD22"4;
"VSS_CD17"
$PN"CD17"4;
"VSS_CD15"
$PN"CD15"4;
"VSS_CD10"
$PN"CD10"4;
"VSS_CD8"
$PN"CD8"4;
"VSS_CD3"
$PN"CD3"4;
"VSS_CC75"
$PN"CC75"4;
"VSS_CC72"
$PN"CC72"4;
"VSS_CC70"
$PN"CC70"4;
"VSS_CC68"
$PN"CC68"4;
"VSS_CC65"
$PN"CC65"4;
"VSS_CC63"
$PN"CC63"4;
"VSS_CC61"
$PN"CC61"4;
"VSS_CC58"
$PN"CC58"4;
"VSS_CC56"
$PN"CC56"4;
"VSS_CC54"
$PN"CC54"4;
"VSS_CC51"
$PN"CC51"4;
"VSS_CC48"
$PN"CC48"4;
"VSS_CC45"
$PN"CC45"4;
"VSS_CC42"
$PN"CC42"4;
"VSS_CC34"
$PN"CC34"4;
"VSS_CC31"
$PN"CC31"4;
"VSS_CC28"
$PN"CC28"4;
"VSS_CC25"
$PN"CC25"4;
"VSS_CC20"
$PN"CC20"4;
"VSS_CC18"
$PN"CC18"4;
"VSS_CC15"
$PN"CC15"4;
"VSS_CC13"
$PN"CC13"4;
"VSS_CC11"
$PN"CC11"4;
"VSS_CC8"
$PN"CC8"4;
"VSS_CC6"
$PN"CC6"4;
"VSS_CC4"
$PN"CC4"4;
"VSS_CC1"
$PN"CC1"4;
"VSS_CB73"
$PN"CB73"4;
"VSS_CB71"
$PN"CB71"4;
"VSS_CB68"
$PN"CB68"4;
"VSS_CB66"
$PN"CB66"4;
"VSS_CB64"
$PN"CB64"4;
"VSS_CB61"
$PN"CB61"4;
"VSS_CB59"
$PN"CB59"4;
"VSS_CB57"
$PN"CB57"4;
"VSS_CB53"
$PN"CB53"4;
"VSS_CB52"
$PN"CB52"4;
"VSS_CB51"
$PN"CB51"4;
"VSS_CB50"
$PN"CB50"4;
"VSS_CB49"
$PN"CB49"4;
"VSS_CB48"
$PN"CB48"4;
"VSS_CB47"
$PN"CB47"4;
"VSS_CB46"
$PN"CB46"4;
"VSS_CB45"
$PN"CB45"4;
"VSS_CB43"
$PN"CB43"3;
"VSS_CB42"
$PN"CB42"3;
"VSS_CB39"
$PN"CB39"3;
"VSS_CB37"
$PN"CB37"3;
"VSS_CB34"
$PN"CB34"3;
"VSS_CB33"
$PN"CB33"3;
"VSS_CB32"
$PN"CB32"3;
"VSS_CB31"
$PN"CB31"3;
"VSS_CB30"
$PN"CB30"3;
"VSS_CB29"
$PN"CB29"3;
"VSS_CB28"
$PN"CB28"3;
"VSS_CB27"
$PN"CB27"3;
"VSS_CB26"
$PN"CB26"3;
"VSS_CB25"
$PN"CB25"3;
"VSS_CB24"
$PN"CB24"3;
"VSS_CB23"
$PN"CB23"3;
"VSS_CB19"
$PN"CB19"3;
"VSS_CB17"
$PN"CB17"3;
"VSS_CB15"
$PN"CB15"3;
"VSS_CB12"
$PN"CB12"3;
"VSS_CB10"
$PN"CB10"3;
"VSS_CB8"
$PN"CB8"3;
"VSS_CB5"
$PN"CB5"3;
"VSS_CB3"
$PN"CB3"3;
"VSS_CA75"
$PN"CA75"3;
"VSS_CA70"
$PN"CA70"3;
"VSS_CA68"
$PN"CA68"3;
"VSS_CA63"
$PN"CA63"3;
"VSS_CA61"
$PN"CA61"3;
"VSS_CA56"
$PN"CA56"3;
"VSS_CA54"
$PN"CA54"3;
"VSS_CA51"
$PN"CA51"3;
"VSS_CA48"
$PN"CA48"3;
"VSS_CA45"
$PN"CA45"3;
"VSS_CA42"
$PN"CA42"3;
"VSS_CA41"
$PN"CA41"3;
"VSS_CA40"
$PN"CA40"3;
"VSS_CA36"
$PN"CA36"3;
"VSS_CA35"
$PN"CA35"3;
"VSS_CA34"
$PN"CA34"3;
"VSS_CA31"
$PN"CA31"3;
"VSS_CA28"
$PN"CA28"3;
"VSS_CA25"
$PN"CA25"3;
"VSS_CA22"
$PN"CA22"3;
"VSS_CA20"
$PN"CA20"3;
"VSS_CA15"
$PN"CA15"3;
"VSS_CA13"
$PN"CA13"3;
"VSS_CA8"
$PN"CA8"3;
"VSS_CA6"
$PN"CA6"3;
"VSS_CA1"
$PN"CA1"3;
"VSS_BY73"
$PN"BY73"3;
"VSS_BY71"
$PN"BY71"3;
"VSS_BY68"
$PN"BY68"3;
"VSS_BY66"
$PN"BY66"3;
"VSS_BY64"
$PN"BY64"3;
"VSS_BY61"
$PN"BY61"3;
"VSS_BY59"
$PN"BY59"3;
"VSS_BY57"
$PN"BY57"3;
"VSS_BY54"
$PN"BY54"3;
"VSS_BY51"
$PN"BY51"3;
"VSS_BY48"
$PN"BY48"3;
"VSS_BY45"
$PN"BY45"3;
"VSS_BY42"
$PN"BY42"3;
"VSS_BY39"
$PN"BY39"3;
"VSS_BY37"
$PN"BY37"3;
"VSS_BY34"
$PN"BY34"3;
"VSS_BY31"
$PN"BY31"3;
"VSS_BY28"
$PN"BY28"3;
"VSS_BY25"
$PN"BY25"3;
"VSS_BY22"
$PN"BY22"3;
"VSS_BY19"
$PN"BY19"3;
"VSS_BY17"
$PN"BY17"3;
"VSS_BY15"
$PN"BY15"3;
"VSS_BY12"
$PN"BY12"3;
"VSS_BY10"
$PN"BY10"3;
"VSS_BY8"
$PN"BY8"3;
"VSS_BY5"
$PN"BY5"3;
"VSS_BY3"
$PN"BY3"3;
"VSS_BW75"
$PN"BW75"3;
"VSS_BW72"
$PN"BW72"3;
"VSS_BW70"
$PN"BW70"3;
"VSS_BW68"
$PN"BW68"3;
"VSS_BW65"
$PN"BW65"3;
"VSS_BW63"
$PN"BW63"3;
"VSS_BW61"
$PN"BW61"3;
"VSS_BW58"
$PN"BW58"3;
"VSS_BW56"
$PN"BW56"3;
"VSS_BW54"
$PN"BW54"3;
"VSS_BW51"
$PN"BW51"3;
"VSS_BW48"
$PN"BW48"3;
"VSS_BW45"
$PN"BW45"3;
"VSS_BW42"
$PN"BW42"3;
"VSS_BW34"
$PN"BW34"3;
"VSS_BW31"
$PN"BW31"3;
"VSS_BW28"
$PN"BW28"3;
"VSS_BW22"
$PN"BW22"3;
"VSS_BW20"
$PN"BW20"3;
"VSS_BW18"
$PN"BW18"3;
"VSS_BW15"
$PN"BW15"3;
"VSS_BW13"
$PN"BW13"3;
"VSS_BW11"
$PN"BW11"3;
"VSS_BW8"
$PN"BW8"3;
"VSS_BW6"
$PN"BW6"3;
"VSS_BW4"
$PN"BW4"3;
"VSS_BW1"
$PN"BW1"3;
"VSS_BV73"
$PN"BV73"3;
"VSS_BV68"
$PN"BV68"3;
"VSS_BV66"
$PN"BV66"3;
"VSS_BV61"
$PN"BV61"3;
"VSS_BV59"
$PN"BV59"3;
"VSS_BV53"
$PN"BV53"3;
"VSS_BV52"
$PN"BV52"3;
"VSS_BV51"
$PN"BV51"3;
"VSS_BV50"
$PN"BV50"3;
"VSS_BV49"
$PN"BV49"3;
"VSS_BV48"
$PN"BV48"3;
"VSS_BV47"
$PN"BV47"3;
"VSS_BV46"
$PN"BV46"3;
%"GENOA_SP5"
"38","(-3875,3475)","0","pure_quanta","I3";
;
LOCATION"U26"
$SEC"38"
CDS_SEC"38"
PART_TYPE"SMLF"
MATERIAL"IO"
VALUE"SOCKET6096_13568-001"
CDS_LIB"pure_quanta"
CDS_LMAN_SYM_OUTLINE"-400,3050,400,-3050"
NEEDS_NO_SIZE"TRUE"
PART_NUMBER"DGA^6000030";
"VSS_CP19"
$PN"CP19"6;
"VSS_CP17"
$PN"CP17"6;
"VSS_CP15"
$PN"CP15"6;
"VSS_CP12"
$PN"CP12"6;
"VSS_CP10"
$PN"CP10"6;
"VSS_CP8"
$PN"CP8"6;
"VSS_CP5"
$PN"CP5"6;
"VSS_CP3"
$PN"CP3"6;
"VSS_CN75"
$PN"CN75"6;
"VSS_CN70"
$PN"CN70"6;
"VSS_CN68"
$PN"CN68"6;
"VSS_CN63"
$PN"CN63"6;
"VSS_CN61"
$PN"CN61"6;
"VSS_CN51"
$PN"CN51"6;
"VSS_CN48"
$PN"CN48"6;
"VSS_CN45"
$PN"CN45"6;
"VSS_CN42"
$PN"CN42"6;
"VSS_CN34"
$PN"CN34"6;
"VSS_CN31"
$PN"CN31"6;
"VSS_CN28"
$PN"CN28"6;
"VSS_CN25"
$PN"CN25"6;
"VSS_CN15"
$PN"CN15"6;
"VSS_CN13"
$PN"CN13"6;
"VSS_CN8"
$PN"CN8"6;
"VSS_CN6"
$PN"CN6"6;
"VSS_CN1"
$PN"CN1"6;
"VSS_CM73"
$PN"CM73"6;
"VSS_CM71"
$PN"CM71"6;
"VSS_CM68"
$PN"CM68"6;
"VSS_CM59"
$PN"CM59"6;
"VSS_CM57"
$PN"CM57"6;
"VSS_CM53"
$PN"CM53"6;
"VSS_CM52"
$PN"CM52"6;
"VSS_CM51"
$PN"CM51"6;
"VSS_CM49"
$PN"CM49"6;
"VSS_CM48"
$PN"CM48"6;
"VSS_CM47"
$PN"CM47"6;
"VSS_CM46"
$PN"CM46"6;
"VSS_CM45"
$PN"CM45"6;
"VSS_CM44"
$PN"CM44"6;
"VSS_CM33"
$PN"CM33"6;
"VSS_CM32"
$PN"CM32"6;
"VSS_CM31"
$PN"CM31"6;
"VSS_CM30"
$PN"CM30"6;
"VSS_CM29"
$PN"CM29"6;
"VSS_CM28"
$PN"CM28"6;
"VSS_CM23"
$PN"CM23"6;
"VSS_CM19"
$PN"CM19"6;
"VSS_CM17"
$PN"CM17"6;
"VSS_CM15"
$PN"CM15"6;
"VSS_CM12"
$PN"CM12"6;
"VSS_CM10"
$PN"CM10"6;
"VSS_CM8"
$PN"CM8"6;
"VSS_CL72"
$PN"CL72"6;
"VSS_CL70"
$PN"CL70"6;
"VSS_CL68"
$PN"CL68"6;
"VSS_CL65"
$PN"CL65"6;
"VSS_CL63"
$PN"CL63"6;
"VSS_CL61"
$PN"CL61"6;
"VSS_CL58"
$PN"CL58"6;
"VSS_CL56"
$PN"CL56"6;
"VSS_CL48"
$PN"CL48"6;
"VSS_CL45"
$PN"CL45"6;
"VSS_CL42"
$PN"CL42"6;
"VSS_CL41"
$PN"CL41"6;
"VSS_CL40"
$PN"CL40"6;
"VSS_CL36"
$PN"CL36"6;
"VSS_CL35"
$PN"CL35"6;
"VSS_CL34"
$PN"CL34"6;
"VSS_CL31"
$PN"CL31"6;
"VSS_CL25"
$PN"CL25"6;
"VSS_CL22"
$PN"CL22"6;
"VSS_CL20"
$PN"CL20"6;
"VSS_CL18"
$PN"CL18"6;
"VSS_CL15"
$PN"CL15"6;
"VSS_CL13"
$PN"CL13"6;
"VSS_CL11"
$PN"CL11"6;
"VSS_CL8"
$PN"CL8"6;
"VSS_CL6"
$PN"CL6"6;
"VSS_CL4"
$PN"CL4"6;
"VSS_CL1"
$PN"CL1"6;
"VSS_CK73"
$PN"CK73"6;
"VSS_CK68"
$PN"CK68"6;
"VSS_CK66"
$PN"CK66"6;
"VSS_CK61"
$PN"CK61"6;
"VSS_CK59"
$PN"CK59"6;
"VSS_CK54"
$PN"CK54"6;
"VSS_CK53"
$PN"CK53"6;
"VSS_CK52"
$PN"CK52"6;
"VSS_CK51"
$PN"CK51"6;
"VSS_CK50"
$PN"CK50"6;
"VSS_CK49"
$PN"CK49"6;
"VSS_CK48"
$PN"CK48"6;
"VSS_CK45"
$PN"CK45"6;
"VSS_CK44"
$PN"CK44"6;
"VSS_CK43"
$PN"CK43"6;
"VSS_CK42"
$PN"CK42"5;
"VSS_CK39"
$PN"CK39"5;
"VSS_CK37"
$PN"CK37"5;
"VSS_CK34"
$PN"CK34"5;
"VSS_CK32"
$PN"CK32"5;
"VSS_CK28"
$PN"CK28"5;
"VSS_CK27"
$PN"CK27"5;
"VSS_CK26"
$PN"CK26"5;
"VSS_CK25"
$PN"CK25"5;
"VSS_CK24"
$PN"CK24"5;
"VSS_CK23"
$PN"CK23"5;
"VSS_CK22"
$PN"CK22"5;
"VSS_CK8"
$PN"CK8"5;
"VSS_CK3"
$PN"CK3"5;
"VSS_CJ75"
$PN"CJ75"5;
"VSS_CJ72"
$PN"CJ72"5;
"VSS_CJ70"
$PN"CJ70"5;
"VSS_CJ68"
$PN"CJ68"5;
"VSS_CJ65"
$PN"CJ65"5;
"VSS_CJ56"
$PN"CJ56"5;
"VSS_CJ45"
$PN"CJ45"5;
"VSS_CJ42"
$PN"CJ42"5;
"VSS_CJ41"
$PN"CJ41"5;
"VSS_CJ40"
$PN"CJ40"5;
"VSS_CJ36"
$PN"CJ36"5;
"VSS_CJ35"
$PN"CJ35"5;
"VSS_CJ18"
$PN"CJ18"5;
"VSS_CJ15"
$PN"CJ15"5;
"VSS_CJ13"
$PN"CJ13"5;
"VSS_CJ11"
$PN"CJ11"5;
"VSS_CJ8"
$PN"CJ8"5;
"VSS_CJ6"
$PN"CJ6"5;
"VSS_CH66"
$PN"CH66"5;
"VSS_CH64"
$PN"CH64"5;
"VSS_CH61"
$PN"CH61"5;
"VSS_CH59"
$PN"CH59"5;
"VSS_CH57"
$PN"CH57"5;
"VSS_CH54"
$PN"CH54"5;
"VSS_CH37"
$PN"CH37"5;
"VSS_CH34"
$PN"CH34"5;
"VSS_CH31"
$PN"CH31"5;
"VSS_CH28"
$PN"CH28"5;
"VSS_CH25"
$PN"CH25"5;
"VSS_CH22"
$PN"CH22"5;
"VSS_CH8"
$PN"CH8"5;
"VSS_CH5"
$PN"CH5"5;
"VSS_CH3"
$PN"CH3"5;
"VSS_CG75"
$PN"CG75"5;
"VSS_CG70"
$PN"CG70"5;
"VSS_CG68"
$PN"CG68"5;
"VSS_CG63"
$PN"CG63"5;
"VSS_CG61"
$PN"CG61"5;
"VSS_CG56"
$PN"CG56"5;
"VSS_CG54"
$PN"CG54"5;
"VSS_CG51"
$PN"CG51"5;
"VSS_CG48"
$PN"CG48"5;
"VSS_CG45"
$PN"CG45"5;
"VSS_CG34"
$PN"CG34"5;
"VSS_CG31"
$PN"CG31"5;
"VSS_CG28"
$PN"CG28"5;
"VSS_CG25"
$PN"CG25"5;
"VSS_CG22"
$PN"CG22"5;
"VSS_CG20"
$PN"CG20"5;
"VSS_CG15"
$PN"CG15"5;
"VSS_CG13"
$PN"CG13"5;
"VSS_CG8"
$PN"CG8"5;
"VSS_CG6"
$PN"CG6"5;
"VSS_CG1"
$PN"CG1"5;
"VSS_CF73"
$PN"CF73"5;
"VSS_CF71"
$PN"CF71"5;
"VSS_CF68"
$PN"CF68"5;
"VSS_CF66"
$PN"CF66"5;
"VSS_CF64"
$PN"CF64"5;
"VSS_CF61"
$PN"CF61"5;
"VSS_CF59"
$PN"CF59"5;
"VSS_CF57"
$PN"CF57"5;
"VSS_CF53"
$PN"CF53"5;
"VSS_CF52"
$PN"CF52"5;
"VSS_CF51"
$PN"CF51"5;
"VSS_CF50"
$PN"CF50"5;
"VSS_CF49"
$PN"CF49"5;
"VSS_CF48"
$PN"CF48"5;
"VSS_CF47"
$PN"CF47"5;
"VSS_CF45"
$PN"CF45"5;
"VSS_CF44"
$PN"CF44"5;
"VSS_CF43"
$PN"CF43"5;
"VSS_CF42"
$PN"CF42"5;
"VSS_CF39"
$PN"CF39"5;
"VSS_CF37"
$PN"CF37"5;
"VSS_CF34"
$PN"CF34"5;
"VSS_CH19"
$PN"CH19"5;
"VSS_CH51"
$PN"CH51"5;
"VSS_CJ4"
$PN"CJ4"5;
"VSS_CL28"
$PN"CL28"6;
"VSS_CL54"
$PN"CL54"6;
"VSS_CM5"
$PN"CM5"6;
"VSS_CM27"
$PN"CM27"6;
"VSS_CM43"
$PN"CM43"6;
"VSS_CH17"
$PN"CH17"5;
"VSS_CH48"
$PN"CH48"5;
"VSS_CJ1"
$PN"CJ1"5;
"VSS_CJ34"
$PN"CJ34"5;
"VSS_CL51"
$PN"CL51"6;
"VSS_CM3"
$PN"CM3"6;
"VSS_CM26"
$PN"CM26"6;
"VSS_CM42"
$PN"CM42"6;
"VSS_CH15"
$PN"CH15"5;
"VSS_CH45"
$PN"CH45"5;
"VSS_CH73"
$PN"CH73"5;
"VSS_CJ31"
$PN"CJ31"5;
"VSS_CJ63"
$PN"CJ63"5;
"VSS_CL75"
$PN"CL75"6;
"VSS_CM25"
$PN"CM25"6;
"VSS_CM39"
$PN"CM39"6;
"VSS_CM66"
$PN"CM66"6;
"VSS_CH12"
$PN"CH12"5;
"VSS_CH42"
$PN"CH42"5;
"VSS_CH71"
$PN"CH71"5;
"VSS_CJ23"
$PN"CJ23"5;
"VSS_CJ61"
$PN"CJ61"5;
"VSS_CK17"
$PN"CK17"5;
"VSS_CM24"
$PN"CM24"6;
"VSS_CM37"
$PN"CM37"6;
"VSS_CM64"
$PN"CM64"6;
"VSS_CN22"
$PN"CN22"6;
"VSS_CH10"
$PN"CH10"5;
"VSS_CH39"
$PN"CH39"5;
"VSS_CH68"
$PN"CH68"5;
"VSS_CJ20"
$PN"CJ20"5;
"VSS_CJ58"
$PN"CJ58"5;
"VSS_CK15"
$PN"CK15"5;
"VSS_CK33"
$PN"CK33"5;
"VSS_CM34"
$PN"CM34"6;
"VSS_CM61"
$PN"CM61"6;
"VSS_CN20"
$PN"CN20"6;
"VSS_CN56"
$PN"CN56"6;
%"GENOA_SP5"
"39","(-1800,3500)","0","pure_quanta","I4";
;
LOCATION"U26"
$SEC"39"
CDS_SEC"39"
PART_TYPE"SMLF"
MATERIAL"IO"
VALUE"SOCKET6096_13568-001"
CDS_LIB"pure_quanta"
CDS_LMAN_SYM_OUTLINE"-400,3050,400,-3050"
NEEDS_NO_SIZE"TRUE"
PART_NUMBER"DGA^6000030";
"VSS_DA70"
$PN"DA70"7;
"VSS_DA68"
$PN"DA68"7;
"VSS_DA65"
$PN"DA65"7;
"VSS_DA63"
$PN"DA63"7;
"VSS_DA61"
$PN"DA61"7;
"VSS_DA58"
$PN"DA58"7;
"VSS_DA42"
$PN"DA42"7;
"VSS_DA34"
$PN"DA34"7;
"VSS_DA31"
$PN"DA31"7;
"VSS_DA28"
$PN"DA28"7;
"VSS_DA25"
$PN"DA25"7;
"VSS_DA22"
$PN"DA22"7;
"VSS_DA11"
$PN"DA11"7;
"VSS_DA8"
$PN"DA8"7;
"VSS_DA6"
$PN"DA6"7;
"VSS_DA4"
$PN"DA4"7;
"VSS_DA1"
$PN"DA1"7;
"VSS_CY73"
$PN"CY73"7;
"VSS_CY71"
$PN"CY71"7;
"VSS_CY61"
$PN"CY61"7;
"VSS_CY59"
$PN"CY59"7;
"VSS_CY53"
$PN"CY53"7;
"VSS_CY52"
$PN"CY52"7;
"VSS_CY51"
$PN"CY51"7;
"VSS_CY50"
$PN"CY50"7;
"VSS_CY49"
$PN"CY49"7;
"VSS_CY46"
$PN"CY46"7;
"VSS_CY45"
$PN"CY45"7;
"VSS_CY44"
$PN"CY44"7;
"VSS_CY43"
$PN"CY43"7;
"VSS_CY42"
$PN"CY42"7;
"VSS_CY39"
$PN"CY39"7;
"VSS_CY37"
$PN"CY37"7;
"VSS_CY34"
$PN"CY34"7;
"VSS_CY33"
$PN"CY33"7;
"VSS_CY31"
$PN"CY31"7;
"VSS_CY30"
$PN"CY30"7;
"VSS_CY29"
$PN"CY29"7;
"VSS_CY28"
$PN"CY28"7;
"VSS_CY27"
$PN"CY27"7;
"VSS_CY26"
$PN"CY26"7;
"VSS_CY25"
$PN"CY25"7;
"VSS_CY24"
$PN"CY24"7;
"VSS_CY23"
$PN"CY23"7;
"VSS_CY19"
$PN"CY19"7;
"VSS_CY17"
$PN"CY17"7;
"VSS_CY15"
$PN"CY15"7;
"VSS_CY12"
$PN"CY12"7;
"VSS_CY10"
$PN"CY10"7;
"VSS_CY8"
$PN"CY8"7;
"VSS_CY5"
$PN"CY5"7;
"VSS_CY3"
$PN"CY3"7;
"VSS_CW75"
$PN"CW75"7;
"VSS_CW70"
$PN"CW70"7;
"VSS_CW68"
$PN"CW68"7;
"VSS_CW63"
$PN"CW63"7;
"VSS_CW61"
$PN"CW61"7;
"VSS_CW56"
$PN"CW56"7;
"VSS_CW54"
$PN"CW54"7;
"VSS_CW51"
$PN"CW51"7;
"VSS_CW48"
$PN"CW48"7;
"VSS_CW45"
$PN"CW45"7;
"VSS_CW42"
$PN"CW42"7;
"VSS_CW41"
$PN"CW41"7;
"VSS_CW40"
$PN"CW40"7;
"VSS_CW36"
$PN"CW36"7;
"VSS_CW35"
$PN"CW35"7;
"VSS_CW20"
$PN"CW20"7;
"VSS_CW15"
$PN"CW15"7;
"VSS_CW13"
$PN"CW13"7;
"VSS_CW8"
$PN"CW8"7;
"VSS_CW6"
$PN"CW6"7;
"VSS_CW1"
$PN"CW1"7;
"VSS_CV61"
$PN"CV61"7;
"VSS_CV59"
$PN"CV59"7;
"VSS_CV57"
$PN"CV57"7;
"VSS_CV54"
$PN"CV54"7;
"VSS_CV51"
$PN"CV51"7;
"VSS_CV48"
$PN"CV48"7;
"VSS_CV31"
$PN"CV31"7;
"VSS_CV28"
$PN"CV28"7;
"VSS_CV25"
$PN"CV25"7;
"VSS_CV22"
$PN"CV22"7;
"VSS_CV19"
$PN"CV19"7;
"VSS_CV17"
$PN"CV17"7;
"VSS_CV3"
$PN"CV3"8;
"VSS_CU75"
$PN"CU75"8;
"VSS_CU72"
$PN"CU72"8;
"VSS_CU70"
$PN"CU70"8;
"VSS_CU68"
$PN"CU68"8;
"VSS_CU65"
$PN"CU65"8;
"VSS_CU54"
$PN"CU54"8;
"VSS_CU51"
$PN"CU51"8;
"VSS_CU48"
$PN"CU48"8;
"VSS_CU45"
$PN"CU45"8;
"VSS_CU42"
$PN"CU42"8;
"VSS_CU34"
$PN"CU34"8;
"VSS_CU31"
$PN"CU31"8;
"VSS_CU20"
$PN"CU20"8;
"VSS_CU18"
$PN"CU18"8;
"VSS_CU15"
$PN"CU15"8;
"VSS_CU13"
$PN"CU13"8;
"VSS_CU11"
$PN"CU11"8;
"VSS_CU8"
$PN"CU8"8;
"VSS_CU6"
$PN"CU6"8;
"VSS_CU4"
$PN"CU4"8;
"VSS_CT68"
$PN"CT68"8;
"VSS_CT66"
$PN"CT66"8;
"VSS_CT61"
$PN"CT61"8;
"VSS_CT59"
$PN"CT59"8;
"VSS_CT53"
$PN"CT53"8;
"VSS_CT51"
$PN"CT51"8;
"VSS_CT50"
$PN"CT50"8;
"VSS_CT49"
$PN"CT49"8;
"VSS_CT47"
$PN"CT47"8;
"VSS_CT46"
$PN"CT46"8;
"VSS_CT45"
$PN"CT45"8;
"VSS_CT44"
$PN"CT44"8;
"VSS_CT43"
$PN"CT43"8;
"VSS_CT42"
$PN"CT42"8;
"VSS_CT39"
$PN"CT39"8;
"VSS_CT37"
$PN"CT37"8;
"VSS_CT34"
$PN"CT34"8;
"VSS_CT33"
$PN"CT33"8;
"VSS_CT32"
$PN"CT32"8;
"VSS_CT31"
$PN"CT31"8;
"VSS_CT30"
$PN"CT30"8;
"VSS_CT29"
$PN"CT29"8;
"VSS_CT28"
$PN"CT28"8;
"VSS_CT27"
$PN"CT27"8;
"VSS_CT26"
$PN"CT26"8;
"VSS_CT25"
$PN"CT25"8;
"VSS_CT24"
$PN"CT24"8;
"VSS_CT23"
$PN"CT23"8;
"VSS_CT17"
$PN"CT17"8;
"VSS_CR72"
$PN"CR72"8;
"VSS_CR70"
$PN"CR70"8;
"VSS_CR68"
$PN"CR68"8;
"VSS_CR65"
$PN"CR65"8;
"VSS_CR63"
$PN"CR63"8;
"VSS_CR61"
$PN"CR61"8;
"VSS_CR45"
$PN"CR45"8;
"VSS_CR42"
$PN"CR42"8;
"VSS_CR41"
$PN"CR41"8;
"VSS_CR40"
$PN"CR40"8;
"VSS_CR36"
$PN"CR36"8;
"VSS_CR35"
$PN"CR35"8;
"VSS_CR20"
$PN"CR20"8;
"VSS_CR18"
$PN"CR18"8;
"VSS_CR15"
$PN"CR15"8;
"VSS_CR13"
$PN"CR13"8;
"VSS_CR11"
$PN"CR11"8;
"VSS_CR8"
$PN"CR8"8;
"VSS_CP68"
$PN"CP68"8;
"VSS_CP66"
$PN"CP66"8;
"VSS_CP64"
$PN"CP64"8;
"VSS_CP61"
$PN"CP61"8;
"VSS_CP59"
$PN"CP59"8;
"VSS_CP57"
$PN"CP57"8;
"VSS_CP39"
$PN"CP39"8;
"VSS_CP37"
$PN"CP37"8;
"VSS_CP34"
$PN"CP34"8;
"VSS_CP31"
$PN"CP31"8;
"VSS_CP28"
$PN"CP28"8;
"VSS_CP25"
$PN"CP25"8;
"VSS_DA54"
$PN"DA54"7;
"VSS_DA51"
$PN"DA51"7;
"VSS_DA48"
$PN"DA48"7;
"VSS_DA45"
$PN"DA45"7;
"VSS_DA20"
$PN"DA20"7;
"VSS_DA18"
$PN"DA18"7;
"VSS_DA15"
$PN"DA15"7;
"VSS_DA13"
$PN"DA13"7;
"VSS_CY68"
$PN"CY68"7;
"VSS_CY66"
$PN"CY66"7;
"VSS_CY64"
$PN"CY64"7;
"VSS_CY48"
$PN"CY48"7;
"VSS_CY47"
$PN"CY47"7;
"VSS_CY32"
$PN"CY32"7;
"VSS_CW34"
$PN"CW34"7;
"VSS_CW31"
$PN"CW31"7;
"VSS_CW28"
$PN"CW28"7;
"VSS_CW25"
$PN"CW25"7;
"VSS_CW22"
$PN"CW22"7;
"VSS_CV73"
$PN"CV73"7;
"VSS_CV71"
$PN"CV71"7;
"VSS_CV68"
$PN"CV68"7;
"VSS_CV66"
$PN"CV66"7;
"VSS_CV64"
$PN"CV64"7;
"VSS_CV45"
$PN"CV45"7;
"VSS_CV42"
$PN"CV42"7;
"VSS_CV39"
$PN"CV39"7;
"VSS_CV37"
$PN"CV37"7;
"VSS_CV34"
$PN"CV34"7;
"VSS_CV15"
$PN"CV15"7;
"VSS_CV12"
$PN"CV12"7;
"VSS_CV10"
$PN"CV10"7;
"VSS_CV8"
$PN"CV8"8;
"VSS_CV5"
$PN"CV5"8;
"VSS_CU63"
$PN"CU63"8;
"VSS_CU61"
$PN"CU61"8;
"VSS_CU56"
$PN"CU56"8;
"VSS_CU28"
$PN"CU28"8;
"VSS_CU25"
$PN"CU25"8;
"VSS_CU22"
$PN"CU22"8;
"VSS_CU1"
$PN"CU1"8;
"VSS_CT73"
$PN"CT73"8;
"VSS_CT48"
$PN"CT48"8;
"VSS_CT15"
$PN"CT15"8;
"VSS_CT10"
$PN"CT10"8;
"VSS_CT8"
$PN"CT8"8;
"VSS_CT3"
$PN"CT3"8;
"VSS_CR75"
$PN"CR75"8;
"VSS_CR58"
$PN"CR58"8;
"VSS_CR56"
$PN"CR56"8;
"VSS_CR54"
$PN"CR54"8;
"VSS_CR51"
$PN"CR51"8;
"VSS_CR48"
$PN"CR48"8;
"VSS_CR34"
$PN"CR34"8;
"VSS_CR31"
$PN"CR31"8;
"VSS_CR28"
$PN"CR28"8;
"VSS_CR25"
$PN"CR25"8;
"VSS_CR22"
$PN"CR22"8;
"VSS_CR6"
$PN"CR6"8;
"VSS_CR4"
$PN"CR4"8;
"VSS_CR1"
$PN"CR1"8;
"VSS_CP73"
$PN"CP73"8;
"VSS_CP71"
$PN"CP71"8;
"VSS_CP54"
$PN"CP54"8;
"VSS_CP51"
$PN"CP51"8;
"VSS_CP48"
$PN"CP48"8;
"VSS_CP45"
$PN"CP45"8;
"VSS_CP42"
$PN"CP42"8;
"VSS_CP22"
$PN"CP22"8;
%"UNIVERSAL_GND"
"1","(-1075,450)","0","pure_quanta_power","I5";
;
CDS_LIB"pure_quanta_power"
HDL_POWER"GND";
"A"8;
%"UNIVERSAL_GND"
"1","(-2525,450)","0","pure_quanta_power","I6";
;
CDS_LIB"pure_quanta_power"
HDL_POWER"GND";
"A"7;
%"UNIVERSAL_GND"
"1","(-3150,450)","0","pure_quanta_power","I7";
;
CDS_LIB"pure_quanta_power"
HDL_POWER"GND";
"A"6;
%"UNIVERSAL_GND"
"1","(-4600,475)","0","pure_quanta_power","I8";
;
CDS_LIB"pure_quanta_power"
HDL_POWER"GND";
"A"5;
%"UNIVERSAL_GND"
"1","(-5225,475)","0","pure_quanta_power","I9";
;
CDS_LIB"pure_quanta_power"
HDL_POWER"GND";
"A"4;
END.
